(kicad_pcb
	(version 20260206)
	(generator "pcbnew")
	(generator_version "10.0")
	(general
		(thickness 1.6)
		(legacy_teardrops no)
	)
	(paper "A4")
	(title_block
		(title "v2-pdb — ms_pdb_v2.brd")
		(comment 1 "Open CloudServer (Microsoft) / footprints 138-146 of 348")
	)
	(layers
		(0 "F.Cu" signal "TOP")
		(4 "In1.Cu" signal "GND")
		(6 "In2.Cu" signal "IN1")
		(8 "In3.Cu" signal "VCC")
		(10 "In4.Cu" signal "VCC1")
		(12 "In5.Cu" signal "IN2")
		(14 "In6.Cu" signal "GND1")
		(2 "B.Cu" signal "BOTTOM")
		(9 "F.Adhes" user "F.Adhesive")
		(11 "B.Adhes" user "B.Adhesive")
		(13 "F.Paste" user "Package Geometry/Pastemask Top")
		(15 "B.Paste" user "Package Geometry/Pastemask Bottom")
		(5 "F.SilkS" user "Ref Des/Silkscreen Top")
		(7 "B.SilkS" user "Ref Des/Silkscreen Bottom")
		(1 "F.Mask" user "Board Geometry/Soldermask Top")
		(3 "B.Mask" user "Board Geometry/Soldermask Bottom")
		(17 "Dwgs.User" user "User.Drawings")
		(19 "Cmts.User" user "User.Comments")
		(21 "Eco1.User" user "User.Eco1")
		(23 "Eco2.User" user "User.Eco2")
		(25 "Edge.Cuts" user "Board Geometry/Outline")
		(27 "Margin" user)
		(31 "F.CrtYd" user "Package Geometry/Place Bound Top")
		(29 "B.CrtYd" user "Package Geometry/Place Bound Bottom")
		(35 "F.Fab" user "Ref Des/Assembly Top")
		(33 "B.Fab" user "Ref Des/Assembly Bottom")
	)
	(footprint ""
		(layer "F.Cu")
		(at 39.581836 -376.389646 -90)
		(property "Reference" "R102"
			(at -0.894842 -0.166878 90)
			(unlocked yes)
			(layer "F.SilkS")
			(effects
				(font
					(size 0.7874 0.5842)
					(thickness 0.1524)
				)
				(justify left)
			)
		)
		(property "Value" ""
			(at 0 0 270)
			(layer "F.Fab")
			(effects
				(font
					(size 1.27 1.27)
				)
			)
		)
		(duplicate_pad_numbers_are_jumpers no)
		(fp_line
			(start -0.7874 0.4064)
			(end -0.7874 -0.4064)
			(stroke
				(width 0.1524)
				(type default)
			)
			(layer "F.SilkS")
		)
		(fp_line
			(start 0.7874 0.4064)
			(end -0.7874 0.4064)
			(stroke
				(width 0.1524)
				(type default)
			)
			(layer "F.SilkS")
		)
		(fp_line
			(start -0.7874 -0.4064)
			(end 0.7874 -0.4064)
			(stroke
				(width 0.1524)
				(type default)
			)
			(layer "F.SilkS")
		)
		(fp_line
			(start 0.7874 -0.4064)
			(end 0.7874 0.4064)
			(stroke
				(width 0.1524)
				(type default)
			)
			(layer "F.SilkS")
		)
		(fp_poly
			(pts
				(xy -0.508 0.2794) (xy -0.508 0.2286) (xy -0.635 0.2286) (xy -0.635 -0.254) (xy -0.5334 -0.254)
				(xy -0.5334 -0.2794) (xy 0.5334 -0.2794) (xy 0.5334 -0.254) (xy 0.635 -0.254) (xy 0.635 0.254) (xy 0.5334 0.254)
				(xy 0.5334 0.2794)
			)
			(stroke
				(width 0)
				(type default)
			)
			(fill no)
			(layer "F.CrtYd")
		)
		(pad "1" smd rect
			(at 0.40005 0 270)
			(size 0.4572 0.508)
			(layers "F.Cu" "F.Mask" "F.Paste")
			(net "PSU5_REMOTE_P")
		)
		(pad "2" smd rect
			(at -0.40005 0 270)
			(size 0.4572 0.508)
			(layers "F.Cu" "F.Mask" "F.Paste")
			(net "PSU5_REMOTE_R_P")
		)
	)
	(footprint ""
		(layer "F.Cu")
		(at 76.299568 -393.452604 90)
		(property "Reference" "C68"
			(at 1.084834 0.192786 90)
			(unlocked yes)
			(layer "F.SilkS")
			(effects
				(font
					(size 0.7874 0.5842)
					(thickness 0.1524)
				)
				(justify left)
			)
		)
		(property "Value" ""
			(at 0 0 90)
			(layer "F.Fab")
			(effects
				(font
					(size 1.27 1.27)
				)
			)
		)
		(duplicate_pad_numbers_are_jumpers no)
		(fp_line
			(start 0.7874 -0.4064)
			(end 0.7874 0.4064)
			(stroke
				(width 0.1524)
				(type default)
			)
			(layer "F.SilkS")
		)
		(fp_line
			(start -0.7874 -0.4064)
			(end 0.7874 -0.4064)
			(stroke
				(width 0.1524)
				(type default)
			)
			(layer "F.SilkS")
		)
		(fp_line
			(start 0 0.381)
			(end 0 -0.381)
			(stroke
				(width 0.1524)
				(type default)
			)
			(layer "F.SilkS")
		)
		(fp_line
			(start 0.7874 0.4064)
			(end -0.7874 0.4064)
			(stroke
				(width 0.1524)
				(type default)
			)
			(layer "F.SilkS")
		)
		(fp_line
			(start -0.7874 0.4064)
			(end -0.7874 -0.4064)
			(stroke
				(width 0.1524)
				(type default)
			)
			(layer "F.SilkS")
		)
		(fp_poly
			(pts
				(xy -0.5334 0.254) (xy -0.635 0.254) (xy -0.635 0.2286) (xy -0.635 -0.254) (xy -0.5334 -0.254) (xy -0.5334 -0.2794)
				(xy 0.5334 -0.2794) (xy 0.5334 -0.254) (xy 0.635 -0.254) (xy 0.635 0.254) (xy 0.5334 0.254) (xy 0.5334 0.2794)
				(xy -0.508 0.2794) (xy -0.5334 0.2794)
			)
			(stroke
				(width 0)
				(type default)
			)
			(fill no)
			(layer "F.CrtYd")
		)
		(pad "1" smd rect
			(at 0.40005 0 90)
			(size 0.4572 0.508)
			(layers "F.Cu" "F.Mask" "F.Paste")
			(net "P12V")
		)
		(pad "2" smd rect
			(at -0.40005 0 90)
			(size 0.4572 0.508)
			(layers "F.Cu" "F.Mask" "F.Paste")
			(net "GND")
		)
	)
	(footprint ""
		(layer "F.Cu")
		(at 26.102056 -273.532854)
		(property "Reference" "R76"
			(at -4.037838 -0.005334 0)
			(unlocked yes)
			(layer "F.SilkS")
			(effects
				(font
					(size 0.7874 0.5842)
					(thickness 0.1524)
				)
				(justify left)
			)
		)
		(property "Value" ""
			(at 0 0 0)
			(layer "F.Fab")
			(effects
				(font
					(size 1.27 1.27)
				)
			)
		)
		(duplicate_pad_numbers_are_jumpers no)
		(fp_line
			(start -0.7874 -0.4064)
			(end 0.7874 -0.4064)
			(stroke
				(width 0.1524)
				(type default)
			)
			(layer "F.SilkS")
		)
		(fp_line
			(start -0.7874 0.4064)
			(end -0.7874 -0.4064)
			(stroke
				(width 0.1524)
				(type default)
			)
			(layer "F.SilkS")
		)
		(fp_line
			(start 0.7874 -0.4064)
			(end 0.7874 0.4064)
			(stroke
				(width 0.1524)
				(type default)
			)
			(layer "F.SilkS")
		)
		(fp_line
			(start 0.7874 0.4064)
			(end -0.7874 0.4064)
			(stroke
				(width 0.1524)
				(type default)
			)
			(layer "F.SilkS")
		)
		(fp_poly
			(pts
				(xy -0.508 0.2794) (xy -0.508 0.2286) (xy -0.635 0.2286) (xy -0.635 -0.254) (xy -0.5334 -0.254)
				(xy -0.5334 -0.2794) (xy 0.5334 -0.2794) (xy 0.5334 -0.254) (xy 0.635 -0.254) (xy 0.635 0.254) (xy 0.5334 0.254)
				(xy 0.5334 0.2794)
			)
			(stroke
				(width 0)
				(type default)
			)
			(fill no)
			(layer "F.CrtYd")
		)
		(pad "1" smd rect
			(at 0.40005 0)
			(size 0.4572 0.508)
			(layers "F.Cu" "F.Mask" "F.Paste")
			(net "PSU4_RESET")
		)
		(pad "2" smd rect
			(at -0.40005 0)
			(size 0.4572 0.508)
			(layers "F.Cu" "F.Mask" "F.Paste")
			(net "P12V_STBY")
		)
	)
	(footprint ""
		(layer "F.Cu")
		(at 20.97532 -173.53534 -90)
		(property "Reference" "U3"
			(at -0.45974 -4.01193 0)
			(unlocked yes)
			(layer "F.SilkS")
			(effects
				(font
					(size 0.7874 0.5842)
					(thickness 0.1524)
				)
				(justify left)
			)
		)
		(property "Value" ""
			(at 0 0 270)
			(layer "F.Fab")
			(effects
				(font
					(size 1.27 1.27)
				)
			)
		)
		(duplicate_pad_numbers_are_jumpers no)
		(fp_line
			(start -2.5146 1.4224)
			(end -2.5146 0.4572)
			(stroke
				(width 0.1524)
				(type default)
			)
			(layer "F.SilkS")
		)
		(fp_line
			(start 2.5146 1.4224)
			(end -2.5146 1.4224)
			(stroke
				(width 0.1524)
				(type default)
			)
			(layer "F.SilkS")
		)
		(fp_line
			(start -2.5146 0.4572)
			(end -2.0574 0)
			(stroke
				(width 0.1524)
				(type default)
			)
			(layer "F.SilkS")
		)
		(fp_line
			(start -2.0574 0)
			(end -2.5146 -0.4572)
			(stroke
				(width 0.1524)
				(type default)
			)
			(layer "F.SilkS")
		)
		(fp_line
			(start -2.5146 -0.4572)
			(end -2.5146 -1.4224)
			(stroke
				(width 0.1524)
				(type default)
			)
			(layer "F.SilkS")
		)
		(fp_line
			(start -2.5146 -1.4224)
			(end 2.5146 -1.4224)
			(stroke
				(width 0.1524)
				(type default)
			)
			(layer "F.SilkS")
		)
		(fp_line
			(start 2.5146 -1.4224)
			(end 2.5146 1.4224)
			(stroke
				(width 0.1524)
				(type default)
			)
			(layer "F.SilkS")
		)
		(fp_circle
			(center -1.905 0.889)
			(end -1.905 0.635)
			(stroke
				(width 0.1524)
				(type default)
			)
			(fill no)
			(layer "F.SilkS")
		)
		(fp_poly
			(pts
				(xy -2.1844 3.5052) (xy -2.1844 2.0066) (xy -2.5146 2.0066) (xy -2.5146 -2.0066) (xy -2.1844 -2.0066)
				(xy -2.1844 -3.5052) (xy 2.1844 -3.5052) (xy 2.1844 -2.0066) (xy 2.5146 -2.0066) (xy 2.5146 2.0066)
				(xy 2.1844 2.0066) (xy 2.1844 3.5052)
			)
			(stroke
				(width 0)
				(type default)
			)
			(fill no)
			(layer "F.CrtYd")
		)
		(pad "1" smd rect
			(at -1.905 2.6416 270)
			(size 0.5588 1.7272)
			(layers "F.Cu" "F.Mask" "F.Paste")
			(net "N42263600")
		)
		(pad "2" smd rect
			(at -0.635 2.6416 270)
			(size 0.5588 1.7272)
			(layers "F.Cu" "F.Mask" "F.Paste")
			(net "GND")
		)
		(pad "3" smd rect
			(at 0.635 2.6416 270)
			(size 0.5588 1.7272)
			(layers "F.Cu" "F.Mask" "F.Paste")
			(net "GND")
		)
		(pad "4" smd rect
			(at 1.905 2.6416 270)
			(size 0.5588 1.7272)
			(layers "F.Cu" "F.Mask" "F.Paste")
			(net "Net_452")
		)
		(pad "5" smd rect
			(at 1.905 -2.6416 270)
			(size 0.5588 1.7272)
			(layers "F.Cu" "F.Mask" "F.Paste")
			(net "Net_451")
		)
		(pad "6" smd rect
			(at 0.635 -2.6416 270)
			(size 0.5588 1.7272)
			(layers "F.Cu" "F.Mask" "F.Paste")
			(net "GND")
		)
		(pad "7" smd rect
			(at -0.635 -2.6416 270)
			(size 0.5588 1.7272)
			(layers "F.Cu" "F.Mask" "F.Paste")
			(net "GND")
		)
		(pad "8" smd rect
			(at -1.905 -2.6416 270)
			(size 0.5588 1.7272)
			(layers "F.Cu" "F.Mask" "F.Paste")
			(net "N42264085")
		)
	)
	(footprint ""
		(layer "F.Cu")
		(at 72.932798 -473.59951 180)
		(property "Reference" "R131"
			(at 0.900176 1.046988 0)
			(unlocked yes)
			(layer "F.SilkS")
			(effects
				(font
					(size 0.7874 0.5842)
					(thickness 0.1524)
				)
				(justify left)
			)
		)
		(property "Value" ""
			(at 0 0 180)
			(layer "F.Fab")
			(effects
				(font
					(size 1.27 1.27)
				)
			)
		)
		(duplicate_pad_numbers_are_jumpers no)
		(fp_line
			(start 0.7874 0.4064)
			(end -0.7874 0.4064)
			(stroke
				(width 0.1524)
				(type default)
			)
			(layer "F.SilkS")
		)
		(fp_line
			(start 0.7874 -0.4064)
			(end 0.7874 0.4064)
			(stroke
				(width 0.1524)
				(type default)
			)
			(layer "F.SilkS")
		)
		(fp_line
			(start -0.7874 0.4064)
			(end -0.7874 -0.4064)
			(stroke
				(width 0.1524)
				(type default)
			)
			(layer "F.SilkS")
		)
		(fp_line
			(start -0.7874 -0.4064)
			(end 0.7874 -0.4064)
			(stroke
				(width 0.1524)
				(type default)
			)
			(layer "F.SilkS")
		)
		(fp_poly
			(pts
				(xy -0.508 0.2794) (xy -0.508 0.2286) (xy -0.635 0.2286) (xy -0.635 -0.254) (xy -0.5334 -0.254)
				(xy -0.5334 -0.2794) (xy 0.5334 -0.2794) (xy 0.5334 -0.254) (xy 0.635 -0.254) (xy 0.635 0.254) (xy 0.5334 0.254)
				(xy 0.5334 0.2794)
			)
			(stroke
				(width 0)
				(type default)
			)
			(fill no)
			(layer "F.CrtYd")
		)
		(pad "1" smd rect
			(at 0.40005 0 180)
			(size 0.4572 0.508)
			(layers "F.Cu" "F.Mask" "F.Paste")
			(net "PSU6_REMOTE_R2_P")
		)
		(pad "2" smd rect
			(at -0.40005 0 180)
			(size 0.4572 0.508)
			(layers "F.Cu" "F.Mask" "F.Paste")
			(net "P12V")
		)
	)
	(footprint ""
		(layer "F.Cu")
		(at 26.068274 -183.06923)
		(property "Reference" "R55"
			(at -3.997198 0.128524 0)
			(unlocked yes)
			(layer "F.SilkS")
			(effects
				(font
					(size 0.7874 0.5842)
					(thickness 0.1524)
				)
				(justify left)
			)
		)
		(property "Value" ""
			(at 0 0 0)
			(layer "F.Fab")
			(effects
				(font
					(size 1.27 1.27)
				)
			)
		)
		(duplicate_pad_numbers_are_jumpers no)
		(fp_line
			(start -0.7874 -0.4064)
			(end 0.7874 -0.4064)
			(stroke
				(width 0.1524)
				(type default)
			)
			(layer "F.SilkS")
		)
		(fp_line
			(start -0.7874 0.4064)
			(end -0.7874 -0.4064)
			(stroke
				(width 0.1524)
				(type default)
			)
			(layer "F.SilkS")
		)
		(fp_line
			(start 0.7874 -0.4064)
			(end 0.7874 0.4064)
			(stroke
				(width 0.1524)
				(type default)
			)
			(layer "F.SilkS")
		)
		(fp_line
			(start 0.7874 0.4064)
			(end -0.7874 0.4064)
			(stroke
				(width 0.1524)
				(type default)
			)
			(layer "F.SilkS")
		)
		(fp_poly
			(pts
				(xy -0.508 0.2794) (xy -0.508 0.2286) (xy -0.635 0.2286) (xy -0.635 -0.254) (xy -0.5334 -0.254)
				(xy -0.5334 -0.2794) (xy 0.5334 -0.2794) (xy 0.5334 -0.254) (xy 0.635 -0.254) (xy 0.635 0.254) (xy 0.5334 0.254)
				(xy 0.5334 0.2794)
			)
			(stroke
				(width 0)
				(type default)
			)
			(fill no)
			(layer "F.CrtYd")
		)
		(pad "1" smd rect
			(at 0.40005 0)
			(size 0.4572 0.508)
			(layers "F.Cu" "F.Mask" "F.Paste")
			(net "PSU3_RESET")
		)
		(pad "2" smd rect
			(at -0.40005 0)
			(size 0.4572 0.508)
			(layers "F.Cu" "F.Mask" "F.Paste")
			(net "GND")
		)
	)
	(footprint ""
		(layer "F.Cu")
		(at 66.82994 -32.569912 180)
		(property "Reference" "R111"
			(at 1.090422 -1.06934 0)
			(unlocked yes)
			(layer "F.SilkS")
			(effects
				(font
					(size 0.7874 0.5842)
					(thickness 0.1524)
				)
				(justify left)
			)
		)
		(property "Value" ""
			(at 0 0 180)
			(layer "F.Fab")
			(effects
				(font
					(size 1.27 1.27)
				)
			)
		)
		(duplicate_pad_numbers_are_jumpers no)
		(fp_line
			(start 0.7874 0.4064)
			(end -0.7874 0.4064)
			(stroke
				(width 0.1524)
				(type default)
			)
			(layer "F.SilkS")
		)
		(fp_line
			(start 0.7874 -0.4064)
			(end 0.7874 0.4064)
			(stroke
				(width 0.1524)
				(type default)
			)
			(layer "F.SilkS")
		)
		(fp_line
			(start -0.7874 0.4064)
			(end -0.7874 -0.4064)
			(stroke
				(width 0.1524)
				(type default)
			)
			(layer "F.SilkS")
		)
		(fp_line
			(start -0.7874 -0.4064)
			(end 0.7874 -0.4064)
			(stroke
				(width 0.1524)
				(type default)
			)
			(layer "F.SilkS")
		)
		(fp_poly
			(pts
				(xy -0.508 0.2794) (xy -0.508 0.2286) (xy -0.635 0.2286) (xy -0.635 -0.254) (xy -0.5334 -0.254)
				(xy -0.5334 -0.2794) (xy 0.5334 -0.2794) (xy 0.5334 -0.254) (xy 0.635 -0.254) (xy 0.635 0.254) (xy 0.5334 0.254)
				(xy 0.5334 0.2794)
			)
			(stroke
				(width 0)
				(type default)
			)
			(fill no)
			(layer "F.CrtYd")
		)
		(pad "1" smd rect
			(at 0.40005 0 180)
			(size 0.4572 0.508)
			(layers "F.Cu" "F.Mask" "F.Paste")
			(net "PSU1_REMOTE_R2_P")
		)
		(pad "2" smd rect
			(at -0.40005 0 180)
			(size 0.4572 0.508)
			(layers "F.Cu" "F.Mask" "F.Paste")
			(net "P12V")
		)
	)
	(footprint ""
		(layer "F.Cu")
		(at 72.802242 -463.542634 -90)
		(property "Reference" "C72"
			(at -2.840736 0.698754 90)
			(unlocked yes)
			(layer "F.SilkS")
			(effects
				(font
					(size 0.7874 0.5842)
					(thickness 0.1524)
				)
				(justify left)
			)
		)
		(property "Value" ""
			(at 0 0 270)
			(layer "F.Fab")
			(effects
				(font
					(size 1.27 1.27)
				)
			)
		)
		(duplicate_pad_numbers_are_jumpers no)
		(fp_line
			(start -0.7874 0.4064)
			(end -0.7874 -0.4064)
			(stroke
				(width 0.1524)
				(type default)
			)
			(layer "F.SilkS")
		)
		(fp_line
			(start 0.7874 0.4064)
			(end -0.7874 0.4064)
			(stroke
				(width 0.1524)
				(type default)
			)
			(layer "F.SilkS")
		)
		(fp_line
			(start 0 0.381)
			(end 0 -0.381)
			(stroke
				(width 0.1524)
				(type default)
			)
			(layer "F.SilkS")
		)
		(fp_line
			(start -0.7874 -0.4064)
			(end 0.7874 -0.4064)
			(stroke
				(width 0.1524)
				(type default)
			)
			(layer "F.SilkS")
		)
		(fp_line
			(start 0.7874 -0.4064)
			(end 0.7874 0.4064)
			(stroke
				(width 0.1524)
				(type default)
			)
			(layer "F.SilkS")
		)
		(fp_poly
			(pts
				(xy -0.5334 0.254) (xy -0.635 0.254) (xy -0.635 0.2286) (xy -0.635 -0.254) (xy -0.5334 -0.254) (xy -0.5334 -0.2794)
				(xy 0.5334 -0.2794) (xy 0.5334 -0.254) (xy 0.635 -0.254) (xy 0.635 0.254) (xy 0.5334 0.254) (xy 0.5334 0.2794)
				(xy -0.508 0.2794) (xy -0.5334 0.2794)
			)
			(stroke
				(width 0)
				(type default)
			)
			(fill no)
			(layer "F.CrtYd")
		)
		(pad "1" smd rect
			(at 0.40005 0 270)
			(size 0.4572 0.508)
			(layers "F.Cu" "F.Mask" "F.Paste")
			(net "P12V")
		)
		(pad "2" smd rect
			(at -0.40005 0 270)
			(size 0.4572 0.508)
			(layers "F.Cu" "F.Mask" "F.Paste")
			(net "GND")
		)
	)
	(footprint ""
		(layer "F.Cu")
		(at 40.056562 -281.140662 180)
		(property "Reference" "R25"
			(at -1.619504 -0.058166 0)
			(unlocked yes)
			(layer "F.SilkS")
			(effects
				(font
					(size 0.7874 0.5842)
					(thickness 0.1524)
				)
				(justify left)
			)
		)
		(property "Value" ""
			(at 0 0 180)
			(layer "F.Fab")
			(effects
				(font
					(size 1.27 1.27)
				)
			)
		)
		(duplicate_pad_numbers_are_jumpers no)
		(fp_line
			(start 0.7874 0.4064)
			(end -0.7874 0.4064)
			(stroke
				(width 0.1524)
				(type default)
			)
			(layer "F.SilkS")
		)
		(fp_line
			(start 0.7874 -0.4064)
			(end 0.7874 0.4064)
			(stroke
				(width 0.1524)
				(type default)
			)
			(layer "F.SilkS")
		)
		(fp_line
			(start -0.7874 0.4064)
			(end -0.7874 -0.4064)
			(stroke
				(width 0.1524)
				(type default)
			)
			(layer "F.SilkS")
		)
		(fp_line
			(start -0.7874 -0.4064)
			(end 0.7874 -0.4064)
			(stroke
				(width 0.1524)
				(type default)
			)
			(layer "F.SilkS")
		)
		(fp_poly
			(pts
				(xy -0.508 0.2794) (xy -0.508 0.2286) (xy -0.635 0.2286) (xy -0.635 -0.254) (xy -0.5334 -0.254)
				(xy -0.5334 -0.2794) (xy 0.5334 -0.2794) (xy 0.5334 -0.254) (xy 0.635 -0.254) (xy 0.635 0.254) (xy 0.5334 0.254)
				(xy 0.5334 0.2794)
			)
			(stroke
				(width 0)
				(type default)
			)
			(fill no)
			(layer "F.CrtYd")
		)
		(pad "1" smd rect
			(at 0.40005 0 180)
			(size 0.4572 0.508)
			(layers "F.Cu" "F.Mask" "F.Paste")
			(net "PSU4_RETURN")
		)
		(pad "2" smd rect
			(at -0.40005 0 180)
			(size 0.4572 0.508)
			(layers "F.Cu" "F.Mask" "F.Paste")
			(net "GND")
		)
	)
)
